# T6G (Grand Teton) — schematic netlist excerpt (pin names and nets, part order shuffled) for the footprints in the layout excerpt that follows; sources: Cadence DE-HDL packaged netlist, KiCad conversion of 04192023_DAF0TMB3IC0_F0TG_MB_C_brd_V02_OCP.brd

PR344  Q_RES  2.2 1% CHIP  pkg 0402LF  page 195 : A = PVDDCR_CPU0_P0_PVCC ; B = PVDDCR_CPU0_P0_VCC3
C26  Q_CAP  0.1UF 25V 10% X7R  pkg 0402  page 160 : A = P3V3 ; B = GND

(kicad_pcb
	(version 20260206)
	(generator "pcbnew")
	(generator_version "10.0")
	(general
		(thickness 1.6)
		(legacy_teardrops no)
	)
	(paper "A4")
	(title_block
		(title "04192023_DAF0TMB3IC0_F0TG_MB_C_brd_V02_OCP.brd")
		(comment 1 "Grand Teton / footprints 5718-5719 of 8354")
	)
	(layers
		(0 "F.Cu" signal "TOP")
		(4 "In1.Cu" signal "GND")
		(6 "In2.Cu" signal "IN1")
		(8 "In3.Cu" signal "GND1")
		(10 "In4.Cu" signal "IN2")
		(12 "In5.Cu" signal "GND2")
		(14 "In6.Cu" signal "IN3")
		(16 "In7.Cu" signal "GND3")
		(18 "In8.Cu" signal "VCC")
		(20 "In9.Cu" signal "VCC1")
		(22 "In10.Cu" signal "GND4")
		(24 "In11.Cu" signal "IN4")
		(26 "In12.Cu" signal "GND5")
		(28 "In13.Cu" signal "IN5")
		(30 "In14.Cu" signal "GND6")
		(32 "In15.Cu" signal "IN6")
		(34 "In16.Cu" signal "GND7")
		(2 "B.Cu" signal "BOTTOM")
		(9 "F.Adhes" user "F.Adhesive")
		(11 "B.Adhes" user "B.Adhesive")
		(13 "F.Paste" user "Package Geometry/Pastemask Top")
		(15 "B.Paste" user "Package Geometry/Pastemask Bottom")
		(5 "F.SilkS" user "Ref Des/Silkscreen Top")
		(7 "B.SilkS" user "Ref Des/Silkscreen Bottom")
		(1 "F.Mask" user "Board Geometry/Soldermask Top")
		(3 "B.Mask" user "Board Geometry/Soldermask Bottom")
		(17 "Dwgs.User" user "User.Drawings")
		(19 "Cmts.User" user "User.Comments")
		(21 "Eco1.User" user "User.Eco1")
		(23 "Eco2.User" user "User.Eco2")
		(25 "Edge.Cuts" user "Board Geometry/Outline")
		(27 "Margin" user)
		(31 "F.CrtYd" user "Package Geometry/Place Bound Top")
		(29 "B.CrtYd" user "Package Geometry/Place Bound Bottom")
		(35 "F.Fab" user "Ref Des/Assembly Top")
		(33 "B.Fab" user "Ref Des/Assembly Bottom")
	)
	(footprint ""
		(layer "B.Cu")
		(at 383.38887 -181.684676 90)
		(property "Reference" "PR344"
			(at 0 0 90)
			(layer "B.SilkS")
			(hide yes)
			(effects
				(font
					(size 1.27 1.27)
				)
				(justify mirror)
			)
		)
		(property "Value" ""
			(at 0 0 90)
			(layer "B.Fab")
			(effects
				(font
					(size 1.27 1.27)
				)
				(justify mirror)
			)
		)
		(duplicate_pad_numbers_are_jumpers no)
		(fp_line
			(start 0.7874 -0.4064)
			(end -0.7874 -0.4064)
			(stroke
				(width 0.1524)
				(type default)
			)
			(layer "B.SilkS")
		)
		(fp_line
			(start -0.7874 -0.4064)
			(end -0.7874 0.4064)
			(stroke
				(width 0.1524)
				(type default)
			)
			(layer "B.SilkS")
		)
		(fp_line
			(start 0.7874 0.4064)
			(end 0.7874 -0.4064)
			(stroke
				(width 0.1524)
				(type default)
			)
			(layer "B.SilkS")
		)
		(fp_line
			(start -0.7874 0.4064)
			(end 0.7874 0.4064)
			(stroke
				(width 0.1524)
				(type default)
			)
			(layer "B.SilkS")
		)
		(fp_line
			(start 0.67945 -0.305054)
			(end 0.12065 -0.305054)
			(stroke
				(width 0.1)
				(type default)
			)
			(layer "B.Fab")
		)
		(fp_line
			(start 0.12065 -0.305054)
			(end 0.12065 -0.2794)
			(stroke
				(width 0.1)
				(type default)
			)
			(layer "B.Fab")
		)
		(fp_line
			(start -0.12065 -0.3048)
			(end -0.67945 -0.3048)
			(stroke
				(width 0.1)
				(type default)
			)
			(layer "B.Fab")
		)
		(fp_line
			(start -0.67945 -0.3048)
			(end -0.67945 0.3048)
			(stroke
				(width 0.1)
				(type default)
			)
			(layer "B.Fab")
		)
		(fp_line
			(start 0.12065 -0.2794)
			(end -0.12065 -0.2794)
			(stroke
				(width 0.1)
				(type default)
			)
			(layer "B.Fab")
		)
		(fp_line
			(start -0.12065 -0.2794)
			(end -0.12065 -0.3048)
			(stroke
				(width 0.1)
				(type default)
			)
			(layer "B.Fab")
		)
		(fp_line
			(start 0.12065 0.2794)
			(end 0.12065 0.3048)
			(stroke
				(width 0.1)
				(type default)
			)
			(layer "B.Fab")
		)
		(fp_line
			(start -0.120396 0.2794)
			(end 0.12065 0.2794)
			(stroke
				(width 0.1)
				(type default)
			)
			(layer "B.Fab")
		)
		(fp_line
			(start 0.67945 0.3048)
			(end 0.67945 -0.305054)
			(stroke
				(width 0.1)
				(type default)
			)
			(layer "B.Fab")
		)
		(fp_line
			(start 0.12065 0.3048)
			(end 0.67945 0.3048)
			(stroke
				(width 0.1)
				(type default)
			)
			(layer "B.Fab")
		)
		(fp_line
			(start -0.120396 0.3048)
			(end -0.120396 0.2794)
			(stroke
				(width 0.1)
				(type default)
			)
			(layer "B.Fab")
		)
		(fp_line
			(start -0.67945 0.3048)
			(end -0.120396 0.3048)
			(stroke
				(width 0.1)
				(type default)
			)
			(layer "B.Fab")
		)
		(pad "1" smd circle
			(at 0.40005 0 270)
			(size 0 0)
			(layers "B.Cu" "B.Mask" "B.Paste")
			(net "PVDDCR_CPU0_P0_PVCC")
		)
		(pad "2" smd circle
			(at -0.40005 0 270)
			(size 0 0)
			(layers "B.Cu" "B.Mask" "B.Paste")
			(net "PVDDCR_CPU0_P0_VCC3")
		)
	)
	(footprint ""
		(layer "B.Cu")
		(at 237.236 -219.075 90)
		(property "Reference" "C26"
			(at 0 0 90)
			(layer "B.SilkS")
			(hide yes)
			(effects
				(font
					(size 1.27 1.27)
				)
				(justify mirror)
			)
		)
		(property "Value" ""
			(at 0 0 90)
			(layer "B.Fab")
			(effects
				(font
					(size 1.27 1.27)
				)
				(justify mirror)
			)
		)
		(duplicate_pad_numbers_are_jumpers no)
		(fp_line
			(start 0.7874 -0.4064)
			(end -0.7874 -0.4064)
			(stroke
				(width 0.1524)
				(type default)
			)
			(layer "B.SilkS")
		)
		(fp_line
			(start -0.7874 -0.4064)
			(end -0.7874 0.4064)
			(stroke
				(width 0.1524)
				(type default)
			)
			(layer "B.SilkS")
		)
		(fp_line
			(start 0.7874 0.4064)
			(end 0.7874 -0.4064)
			(stroke
				(width 0.1524)
				(type default)
			)
			(layer "B.SilkS")
		)
		(fp_line
			(start -0.7874 0.4064)
			(end 0.7874 0.4064)
			(stroke
				(width 0.1524)
				(type default)
			)
			(layer "B.SilkS")
		)
		(fp_line
			(start 0.67945 -0.305054)
			(end 0.12065 -0.305054)
			(stroke
				(width 0.1)
				(type default)
			)
			(layer "B.Fab")
		)
		(fp_line
			(start 0.12065 -0.305054)
			(end 0.12065 -0.2794)
			(stroke
				(width 0.1)
				(type default)
			)
			(layer "B.Fab")
		)
		(fp_line
			(start -0.12065 -0.3048)
			(end -0.67945 -0.3048)
			(stroke
				(width 0.1)
				(type default)
			)
			(layer "B.Fab")
		)
		(fp_line
			(start -0.67945 -0.3048)
			(end -0.67945 0.3048)
			(stroke
				(width 0.1)
				(type default)
			)
			(layer "B.Fab")
		)
		(fp_line
			(start 0.12065 -0.2794)
			(end -0.12065 -0.2794)
			(stroke
				(width 0.1)
				(type default)
			)
			(layer "B.Fab")
		)
		(fp_line
			(start -0.12065 -0.2794)
			(end -0.12065 -0.3048)
			(stroke
				(width 0.1)
				(type default)
			)
			(layer "B.Fab")
		)
		(fp_line
			(start 0.12065 0.2794)
			(end 0.12065 0.3048)
			(stroke
				(width 0.1)
				(type default)
			)
			(layer "B.Fab")
		)
		(fp_line
			(start -0.120396 0.2794)
			(end 0.12065 0.2794)
			(stroke
				(width 0.1)
				(type default)
			)
			(layer "B.Fab")
		)
		(fp_line
			(start 0.67945 0.3048)
			(end 0.67945 -0.305054)
			(stroke
				(width 0.1)
				(type default)
			)
			(layer "B.Fab")
		)
		(fp_line
			(start 0.12065 0.3048)
			(end 0.67945 0.3048)
			(stroke
				(width 0.1)
				(type default)
			)
			(layer "B.Fab")
		)
		(fp_line
			(start -0.120396 0.3048)
			(end -0.120396 0.2794)
			(stroke
				(width 0.1)
				(type default)
			)
			(layer "B.Fab")
		)
		(fp_line
			(start -0.67945 0.3048)
			(end -0.120396 0.3048)
			(stroke
				(width 0.1)
				(type default)
			)
			(layer "B.Fab")
		)
		(pad "1" smd circle
			(at 0.40005 0 270)
			(size 0 0)
			(layers "B.Cu" "B.Mask" "B.Paste")
			(net "P3V3")
		)
		(pad "2" smd circle
			(at -0.40005 0 270)
			(size 0 0)
			(layers "B.Cu" "B.Mask" "B.Paste")
			(net "GND")
		)
	)
)
